(kicad_pcb
	(version 20260206)
	(generator "pcbnew")
	(generator_version "10.0")
	(general
		(thickness 1.6)
		(legacy_teardrops no)
	)
	(paper "A4")
	(title_block
		(title "01162023_DA0F0TEBIF0_F0T_Expander_BD_F_brd_V02_OCP.brd")
		(comment 1 "Grand Teton / footprints 478-484 of 9728")
	)
	(layers
		(0 "F.Cu" signal "TOP")
		(4 "In1.Cu" signal "GND")
		(6 "In2.Cu" signal "VCC")
		(8 "In3.Cu" signal "VCC1")
		(10 "In4.Cu" signal "GND1")
		(12 "In5.Cu" signal "IN1")
		(14 "In6.Cu" signal "GND2")
		(16 "In7.Cu" signal "IN2")
		(18 "In8.Cu" signal "GND3")
		(20 "In9.Cu" signal "IN3")
		(22 "In10.Cu" signal "GND4")
		(24 "In11.Cu" signal "IN4")
		(26 "In12.Cu" signal "GND5")
		(28 "In13.Cu" signal "IN5")
		(30 "In14.Cu" signal "GND6")
		(32 "In15.Cu" signal "IN6")
		(34 "In16.Cu" signal "GND7")
		(2 "B.Cu" signal "BOTTOM")
		(9 "F.Adhes" user "F.Adhesive")
		(11 "B.Adhes" user "B.Adhesive")
		(13 "F.Paste" user "Package Geometry/Pastemask Top")
		(15 "B.Paste" user "Package Geometry/Pastemask Bottom")
		(5 "F.SilkS" user "Ref Des/Silkscreen Top")
		(7 "B.SilkS" user "Ref Des/Silkscreen Bottom")
		(1 "F.Mask" user "Board Geometry/Soldermask Top")
		(3 "B.Mask" user "Board Geometry/Soldermask Bottom")
		(17 "Dwgs.User" user "User.Drawings")
		(19 "Cmts.User" user "User.Comments")
		(21 "Eco1.User" user "User.Eco1")
		(23 "Eco2.User" user "User.Eco2")
		(25 "Edge.Cuts" user "Board Geometry/Outline")
		(27 "Margin" user)
		(31 "F.CrtYd" user "Package Geometry/Place Bound Top")
		(29 "B.CrtYd" user "Package Geometry/Place Bound Bottom")
		(35 "F.Fab" user "Ref Des/Assembly Top")
		(33 "B.Fab" user "Ref Des/Assembly Bottom")
	)
	(footprint ""
		(layer "F.Cu")
		(at 367.954814 -22.867366 90)
		(property "Reference" "C3962"
			(at 0 0 90)
			(layer "F.SilkS")
			(hide yes)
			(effects
				(font
					(size 1.27 1.27)
				)
			)
		)
		(property "Value" ""
			(at 0 0 90)
			(layer "F.Fab")
			(effects
				(font
					(size 1.27 1.27)
				)
			)
		)
		(duplicate_pad_numbers_are_jumpers no)
		(fp_line
			(start 0.7874 -0.4064)
			(end 0.7874 0.4064)
			(stroke
				(width 0.1524)
				(type default)
			)
			(layer "F.SilkS")
		)
		(fp_line
			(start -0.7874 -0.4064)
			(end 0.7874 -0.4064)
			(stroke
				(width 0.1524)
				(type default)
			)
			(layer "F.SilkS")
		)
		(fp_line
			(start 0.7874 0.4064)
			(end -0.7874 0.4064)
			(stroke
				(width 0.1524)
				(type default)
			)
			(layer "F.SilkS")
		)
		(fp_line
			(start -0.7874 0.4064)
			(end -0.7874 -0.4064)
			(stroke
				(width 0.1524)
				(type default)
			)
			(layer "F.SilkS")
		)
		(fp_line
			(start -0.12065 -0.305054)
			(end -0.12065 -0.2794)
			(stroke
				(width 0.1)
				(type default)
			)
			(layer "F.Fab")
		)
		(fp_line
			(start -0.67945 -0.305054)
			(end -0.12065 -0.305054)
			(stroke
				(width 0.1)
				(type default)
			)
			(layer "F.Fab")
		)
		(fp_line
			(start 0.67945 -0.3048)
			(end 0.67945 0.3048)
			(stroke
				(width 0.1)
				(type default)
			)
			(layer "F.Fab")
		)
		(fp_line
			(start 0.12065 -0.3048)
			(end 0.67945 -0.3048)
			(stroke
				(width 0.1)
				(type default)
			)
			(layer "F.Fab")
		)
		(fp_line
			(start 0.12065 -0.2794)
			(end 0.12065 -0.3048)
			(stroke
				(width 0.1)
				(type default)
			)
			(layer "F.Fab")
		)
		(fp_line
			(start -0.12065 -0.2794)
			(end 0.12065 -0.2794)
			(stroke
				(width 0.1)
				(type default)
			)
			(layer "F.Fab")
		)
		(fp_line
			(start 0.120396 0.2794)
			(end -0.12065 0.2794)
			(stroke
				(width 0.1)
				(type default)
			)
			(layer "F.Fab")
		)
		(fp_line
			(start -0.12065 0.2794)
			(end -0.12065 0.3048)
			(stroke
				(width 0.1)
				(type default)
			)
			(layer "F.Fab")
		)
		(fp_line
			(start 0.67945 0.3048)
			(end 0.120396 0.3048)
			(stroke
				(width 0.1)
				(type default)
			)
			(layer "F.Fab")
		)
		(fp_line
			(start 0.120396 0.3048)
			(end 0.120396 0.2794)
			(stroke
				(width 0.1)
				(type default)
			)
			(layer "F.Fab")
		)
		(fp_line
			(start -0.12065 0.3048)
			(end -0.67945 0.3048)
			(stroke
				(width 0.1)
				(type default)
			)
			(layer "F.Fab")
		)
		(fp_line
			(start -0.67945 0.3048)
			(end -0.67945 -0.305054)
			(stroke
				(width 0.1)
				(type default)
			)
			(layer "F.Fab")
		)
		(pad "1" smd circle
			(at -0.40005 0 90)
			(size 0 0)
			(layers "F.Cu" "F.Mask" "F.Paste")
			(net "P12V_SSD12")
		)
		(pad "2" smd circle
			(at 0.40005 0 90)
			(size 0 0)
			(layers "F.Cu" "F.Mask" "F.Paste")
			(net "GND")
		)
	)
	(footprint ""
		(layer "F.Cu")
		(at 421.58285 -80.739742)
		(property "Reference" "R407"
			(at 0 0 0)
			(layer "F.SilkS")
			(hide yes)
			(effects
				(font
					(size 1.27 1.27)
				)
			)
		)
		(property "Value" ""
			(at 0 0 0)
			(layer "F.Fab")
			(effects
				(font
					(size 1.27 1.27)
				)
			)
		)
		(duplicate_pad_numbers_are_jumpers no)
		(fp_line
			(start -0.7874 -0.4064)
			(end 0.7874 -0.4064)
			(stroke
				(width 0.1524)
				(type default)
			)
			(layer "F.SilkS")
		)
		(fp_line
			(start -0.7874 0.4064)
			(end -0.7874 -0.4064)
			(stroke
				(width 0.1524)
				(type default)
			)
			(layer "F.SilkS")
		)
		(fp_line
			(start 0.7874 -0.4064)
			(end 0.7874 0.4064)
			(stroke
				(width 0.1524)
				(type default)
			)
			(layer "F.SilkS")
		)
		(fp_line
			(start 0.7874 0.4064)
			(end -0.7874 0.4064)
			(stroke
				(width 0.1524)
				(type default)
			)
			(layer "F.SilkS")
		)
		(fp_line
			(start -0.67945 -0.305054)
			(end -0.12065 -0.305054)
			(stroke
				(width 0.1)
				(type default)
			)
			(layer "F.Fab")
		)
		(fp_line
			(start -0.67945 0.3048)
			(end -0.67945 -0.305054)
			(stroke
				(width 0.1)
				(type default)
			)
			(layer "F.Fab")
		)
		(fp_line
			(start -0.12065 -0.305054)
			(end -0.12065 -0.2794)
			(stroke
				(width 0.1)
				(type default)
			)
			(layer "F.Fab")
		)
		(fp_line
			(start -0.12065 -0.2794)
			(end 0.12065 -0.2794)
			(stroke
				(width 0.1)
				(type default)
			)
			(layer "F.Fab")
		)
		(fp_line
			(start -0.12065 0.2794)
			(end -0.12065 0.3048)
			(stroke
				(width 0.1)
				(type default)
			)
			(layer "F.Fab")
		)
		(fp_line
			(start -0.12065 0.3048)
			(end -0.67945 0.3048)
			(stroke
				(width 0.1)
				(type default)
			)
			(layer "F.Fab")
		)
		(fp_line
			(start 0.120396 0.2794)
			(end -0.12065 0.2794)
			(stroke
				(width 0.1)
				(type default)
			)
			(layer "F.Fab")
		)
		(fp_line
			(start 0.120396 0.3048)
			(end 0.120396 0.2794)
			(stroke
				(width 0.1)
				(type default)
			)
			(layer "F.Fab")
		)
		(fp_line
			(start 0.12065 -0.3048)
			(end 0.67945 -0.3048)
			(stroke
				(width 0.1)
				(type default)
			)
			(layer "F.Fab")
		)
		(fp_line
			(start 0.12065 -0.2794)
			(end 0.12065 -0.3048)
			(stroke
				(width 0.1)
				(type default)
			)
			(layer "F.Fab")
		)
		(fp_line
			(start 0.67945 -0.3048)
			(end 0.67945 0.3048)
			(stroke
				(width 0.1)
				(type default)
			)
			(layer "F.Fab")
		)
		(fp_line
			(start 0.67945 0.3048)
			(end 0.120396 0.3048)
			(stroke
				(width 0.1)
				(type default)
			)
			(layer "F.Fab")
		)
		(pad "1" smd circle
			(at -0.40005 0)
			(size 0 0)
			(layers "F.Cu" "F.Mask" "F.Paste")
			(net "P3V3_AUX")
		)
		(pad "2" smd circle
			(at 0.40005 0)
			(size 0 0)
			(layers "F.Cu" "F.Mask" "F.Paste")
			(net "HP_NIC7_HSC_PWRGD_N")
		)
	)
	(footprint ""
		(layer "F.Cu")
		(at 384.612134 -137.2489 -90)
		(property "Reference" "C949"
			(at 0 0 270)
			(layer "F.SilkS")
			(hide yes)
			(effects
				(font
					(size 1.27 1.27)
				)
			)
		)
		(property "Value" ""
			(at 0 0 270)
			(layer "F.Fab")
			(effects
				(font
					(size 1.27 1.27)
				)
			)
		)
		(duplicate_pad_numbers_are_jumpers no)
		(fp_line
			(start -0.7874 0.4064)
			(end -0.7874 -0.4064)
			(stroke
				(width 0.1524)
				(type default)
			)
			(layer "F.SilkS")
		)
		(fp_line
			(start 0.7874 0.4064)
			(end -0.7874 0.4064)
			(stroke
				(width 0.1524)
				(type default)
			)
			(layer "F.SilkS")
		)
		(fp_line
			(start -0.7874 -0.4064)
			(end 0.7874 -0.4064)
			(stroke
				(width 0.1524)
				(type default)
			)
			(layer "F.SilkS")
		)
		(fp_line
			(start 0.7874 -0.4064)
			(end 0.7874 0.4064)
			(stroke
				(width 0.1524)
				(type default)
			)
			(layer "F.SilkS")
		)
		(fp_line
			(start -0.67945 0.3048)
			(end -0.67945 -0.305054)
			(stroke
				(width 0.1)
				(type default)
			)
			(layer "F.Fab")
		)
		(fp_line
			(start -0.12065 0.3048)
			(end -0.67945 0.3048)
			(stroke
				(width 0.1)
				(type default)
			)
			(layer "F.Fab")
		)
		(fp_line
			(start 0.120396 0.3048)
			(end 0.120396 0.2794)
			(stroke
				(width 0.1)
				(type default)
			)
			(layer "F.Fab")
		)
		(fp_line
			(start 0.67945 0.3048)
			(end 0.120396 0.3048)
			(stroke
				(width 0.1)
				(type default)
			)
			(layer "F.Fab")
		)
		(fp_line
			(start -0.12065 0.2794)
			(end -0.12065 0.3048)
			(stroke
				(width 0.1)
				(type default)
			)
			(layer "F.Fab")
		)
		(fp_line
			(start 0.120396 0.2794)
			(end -0.12065 0.2794)
			(stroke
				(width 0.1)
				(type default)
			)
			(layer "F.Fab")
		)
		(fp_line
			(start -0.12065 -0.2794)
			(end 0.12065 -0.2794)
			(stroke
				(width 0.1)
				(type default)
			)
			(layer "F.Fab")
		)
		(fp_line
			(start 0.12065 -0.2794)
			(end 0.12065 -0.3048)
			(stroke
				(width 0.1)
				(type default)
			)
			(layer "F.Fab")
		)
		(fp_line
			(start 0.12065 -0.3048)
			(end 0.67945 -0.3048)
			(stroke
				(width 0.1)
				(type default)
			)
			(layer "F.Fab")
		)
		(fp_line
			(start 0.67945 -0.3048)
			(end 0.67945 0.3048)
			(stroke
				(width 0.1)
				(type default)
			)
			(layer "F.Fab")
		)
		(fp_line
			(start -0.67945 -0.305054)
			(end -0.12065 -0.305054)
			(stroke
				(width 0.1)
				(type default)
			)
			(layer "F.Fab")
		)
		(fp_line
			(start -0.12065 -0.305054)
			(end -0.12065 -0.2794)
			(stroke
				(width 0.1)
				(type default)
			)
			(layer "F.Fab")
		)
		(pad "1" smd circle
			(at -0.40005 0 270)
			(size 0 0)
			(layers "F.Cu" "F.Mask" "F.Paste")
			(net "P3V3_NIC6")
		)
		(pad "2" smd circle
			(at 0.40005 0 270)
			(size 0 0)
			(layers "F.Cu" "F.Mask" "F.Paste")
			(net "GND")
		)
	)
	(footprint ""
		(layer "F.Cu")
		(at 80.019398 -154.304746 180)
		(property "Reference" "C3"
			(at 0 0 180)
			(layer "F.SilkS")
			(hide yes)
			(effects
				(font
					(size 1.27 1.27)
				)
			)
		)
		(property "Value" ""
			(at 0 0 180)
			(layer "F.Fab")
			(effects
				(font
					(size 1.27 1.27)
				)
			)
		)
		(duplicate_pad_numbers_are_jumpers no)
		(fp_line
			(start 0.299974 0.150114)
			(end -0.299974 0.150114)
			(stroke
				(width 0.1)
				(type default)
			)
			(layer "F.Fab")
		)
		(fp_line
			(start 0.299974 -0.150114)
			(end 0.299974 0.150114)
			(stroke
				(width 0.1)
				(type default)
			)
			(layer "F.Fab")
		)
		(fp_line
			(start -0.299974 0.150114)
			(end -0.299974 -0.150114)
			(stroke
				(width 0.1)
				(type default)
			)
			(layer "F.Fab")
		)
		(fp_line
			(start -0.299974 -0.150114)
			(end 0.299974 -0.150114)
			(stroke
				(width 0.1)
				(type default)
			)
			(layer "F.Fab")
		)
		(pad "1" smd rect
			(at -0.2667 0 180)
			(size 0.3048 0.381)
			(layers "F.Cu" "F.Mask" "F.Paste")
			(net "P5E_PEX0_STN0_TX_DN<14>")
		)
		(pad "2" smd rect
			(at 0.2667 0 180)
			(size 0.3048 0.381)
			(layers "F.Cu" "F.Mask" "F.Paste")
			(net "P5E_PEX0_STN0_TX_C_DN<14>")
		)
	)
	(footprint ""
		(layer "F.Cu")
		(at 304.634392 -33.631886 180)
		(property "Reference" "C504"
			(at 0 0 180)
			(layer "F.SilkS")
			(hide yes)
			(effects
				(font
					(size 1.27 1.27)
				)
			)
		)
		(property "Value" ""
			(at 0 0 180)
			(layer "F.Fab")
			(effects
				(font
					(size 1.27 1.27)
				)
			)
		)
		(duplicate_pad_numbers_are_jumpers no)
		(fp_line
			(start 0.299974 0.150114)
			(end -0.299974 0.150114)
			(stroke
				(width 0.1)
				(type default)
			)
			(layer "F.Fab")
		)
		(fp_line
			(start 0.299974 -0.150114)
			(end 0.299974 0.150114)
			(stroke
				(width 0.1)
				(type default)
			)
			(layer "F.Fab")
		)
		(fp_line
			(start -0.299974 0.150114)
			(end -0.299974 -0.150114)
			(stroke
				(width 0.1)
				(type default)
			)
			(layer "F.Fab")
		)
		(fp_line
			(start -0.299974 -0.150114)
			(end 0.299974 -0.150114)
			(stroke
				(width 0.1)
				(type default)
			)
			(layer "F.Fab")
		)
		(pad "1" smd rect
			(at -0.2667 0 180)
			(size 0.3048 0.381)
			(layers "F.Cu" "F.Mask" "F.Paste")
			(net "P5E_PEX2_STN2_TX_DN<39>")
		)
		(pad "2" smd rect
			(at 0.2667 0 180)
			(size 0.3048 0.381)
			(layers "F.Cu" "F.Mask" "F.Paste")
			(net "P5E_PEX2_STN2_TX_C_DN<39>")
		)
	)
	(footprint ""
		(layer "F.Cu")
		(at 45.654722 -22.867366 90)
		(property "Reference" "C3880"
			(at 0 0 90)
			(layer "F.SilkS")
			(hide yes)
			(effects
				(font
					(size 1.27 1.27)
				)
			)
		)
		(property "Value" ""
			(at 0 0 90)
			(layer "F.Fab")
			(effects
				(font
					(size 1.27 1.27)
				)
			)
		)
		(duplicate_pad_numbers_are_jumpers no)
		(fp_line
			(start 0.7874 -0.4064)
			(end 0.7874 0.4064)
			(stroke
				(width 0.1524)
				(type default)
			)
			(layer "F.SilkS")
		)
		(fp_line
			(start -0.7874 -0.4064)
			(end 0.7874 -0.4064)
			(stroke
				(width 0.1524)
				(type default)
			)
			(layer "F.SilkS")
		)
		(fp_line
			(start 0.7874 0.4064)
			(end -0.7874 0.4064)
			(stroke
				(width 0.1524)
				(type default)
			)
			(layer "F.SilkS")
		)
		(fp_line
			(start -0.7874 0.4064)
			(end -0.7874 -0.4064)
			(stroke
				(width 0.1524)
				(type default)
			)
			(layer "F.SilkS")
		)
		(fp_line
			(start -0.12065 -0.305054)
			(end -0.12065 -0.2794)
			(stroke
				(width 0.1)
				(type default)
			)
			(layer "F.Fab")
		)
		(fp_line
			(start -0.67945 -0.305054)
			(end -0.12065 -0.305054)
			(stroke
				(width 0.1)
				(type default)
			)
			(layer "F.Fab")
		)
		(fp_line
			(start 0.67945 -0.3048)
			(end 0.67945 0.3048)
			(stroke
				(width 0.1)
				(type default)
			)
			(layer "F.Fab")
		)
		(fp_line
			(start 0.12065 -0.3048)
			(end 0.67945 -0.3048)
			(stroke
				(width 0.1)
				(type default)
			)
			(layer "F.Fab")
		)
		(fp_line
			(start 0.12065 -0.2794)
			(end 0.12065 -0.3048)
			(stroke
				(width 0.1)
				(type default)
			)
			(layer "F.Fab")
		)
		(fp_line
			(start -0.12065 -0.2794)
			(end 0.12065 -0.2794)
			(stroke
				(width 0.1)
				(type default)
			)
			(layer "F.Fab")
		)
		(fp_line
			(start 0.120396 0.2794)
			(end -0.12065 0.2794)
			(stroke
				(width 0.1)
				(type default)
			)
			(layer "F.Fab")
		)
		(fp_line
			(start -0.12065 0.2794)
			(end -0.12065 0.3048)
			(stroke
				(width 0.1)
				(type default)
			)
			(layer "F.Fab")
		)
		(fp_line
			(start 0.67945 0.3048)
			(end 0.120396 0.3048)
			(stroke
				(width 0.1)
				(type default)
			)
			(layer "F.Fab")
		)
		(fp_line
			(start 0.120396 0.3048)
			(end 0.120396 0.2794)
			(stroke
				(width 0.1)
				(type default)
			)
			(layer "F.Fab")
		)
		(fp_line
			(start -0.12065 0.3048)
			(end -0.67945 0.3048)
			(stroke
				(width 0.1)
				(type default)
			)
			(layer "F.Fab")
		)
		(fp_line
			(start -0.67945 0.3048)
			(end -0.67945 -0.305054)
			(stroke
				(width 0.1)
				(type default)
			)
			(layer "F.Fab")
		)
		(pad "1" smd circle
			(at -0.40005 0 90)
			(size 0 0)
			(layers "F.Cu" "F.Mask" "F.Paste")
			(net "P12V_SSD1")
		)
		(pad "2" smd circle
			(at 0.40005 0 90)
			(size 0 0)
			(layers "F.Cu" "F.Mask" "F.Paste")
			(net "GND")
		)
	)
	(footprint ""
		(layer "F.Cu")
		(at 224.46996 -105.477056)
		(property "Reference" "PC344"
			(at 0 0 0)
			(layer "F.SilkS")
			(hide yes)
			(effects
				(font
					(size 1.27 1.27)
				)
			)
		)
		(property "Value" ""
			(at 0 0 0)
			(layer "F.Fab")
			(effects
				(font
					(size 1.27 1.27)
				)
			)
		)
		(duplicate_pad_numbers_are_jumpers no)
		(fp_line
			(start -0.7874 -0.4064)
			(end 0.7874 -0.4064)
			(stroke
				(width 0.1524)
				(type default)
			)
			(layer "F.SilkS")
		)
		(fp_line
			(start -0.7874 0.4064)
			(end -0.7874 -0.4064)
			(stroke
				(width 0.1524)
				(type default)
			)
			(layer "F.SilkS")
		)
		(fp_line
			(start 0.7874 -0.4064)
			(end 0.7874 0.4064)
			(stroke
				(width 0.1524)
				(type default)
			)
			(layer "F.SilkS")
		)
		(fp_line
			(start 0.7874 0.4064)
			(end -0.7874 0.4064)
			(stroke
				(width 0.1524)
				(type default)
			)
			(layer "F.SilkS")
		)
		(fp_line
			(start -0.67945 -0.305054)
			(end -0.12065 -0.305054)
			(stroke
				(width 0.1)
				(type default)
			)
			(layer "F.Fab")
		)
		(fp_line
			(start -0.67945 0.3048)
			(end -0.67945 -0.305054)
			(stroke
				(width 0.1)
				(type default)
			)
			(layer "F.Fab")
		)
		(fp_line
			(start -0.12065 -0.305054)
			(end -0.12065 -0.2794)
			(stroke
				(width 0.1)
				(type default)
			)
			(layer "F.Fab")
		)
		(fp_line
			(start -0.12065 -0.2794)
			(end 0.12065 -0.2794)
			(stroke
				(width 0.1)
				(type default)
			)
			(layer "F.Fab")
		)
		(fp_line
			(start -0.12065 0.2794)
			(end -0.12065 0.3048)
			(stroke
				(width 0.1)
				(type default)
			)
			(layer "F.Fab")
		)
		(fp_line
			(start -0.12065 0.3048)
			(end -0.67945 0.3048)
			(stroke
				(width 0.1)
				(type default)
			)
			(layer "F.Fab")
		)
		(fp_line
			(start 0.120396 0.2794)
			(end -0.12065 0.2794)
			(stroke
				(width 0.1)
				(type default)
			)
			(layer "F.Fab")
		)
		(fp_line
			(start 0.120396 0.3048)
			(end 0.120396 0.2794)
			(stroke
				(width 0.1)
				(type default)
			)
			(layer "F.Fab")
		)
		(fp_line
			(start 0.12065 -0.3048)
			(end 0.67945 -0.3048)
			(stroke
				(width 0.1)
				(type default)
			)
			(layer "F.Fab")
		)
		(fp_line
			(start 0.12065 -0.2794)
			(end 0.12065 -0.3048)
			(stroke
				(width 0.1)
				(type default)
			)
			(layer "F.Fab")
		)
		(fp_line
			(start 0.67945 -0.3048)
			(end 0.67945 0.3048)
			(stroke
				(width 0.1)
				(type default)
			)
			(layer "F.Fab")
		)
		(fp_line
			(start 0.67945 0.3048)
			(end 0.120396 0.3048)
			(stroke
				(width 0.1)
				(type default)
			)
			(layer "F.Fab")
		)
		(pad "1" smd circle
			(at -0.40005 0)
			(size 0 0)
			(layers "F.Cu" "F.Mask" "F.Paste")
			(net "P12V_NIC3_R")
		)
		(pad "2" smd circle
			(at 0.40005 0)
			(size 0 0)
			(layers "F.Cu" "F.Mask" "F.Paste")
			(net "GND")
		)
	)
)
